# T6G (Grand Teton) — schematic netlist excerpt (pin names and nets, part order shuffled) for the footprints in the layout excerpt that follows; sources: Cadence DE-HDL packaged netlist, KiCad conversion of 04192023_DAF0TMB3IC0_F0TG_MB_C_brd_V02_OCP.brd

R1637  Q_RES  4.7K 5% CHIP  pkg 0402LF  page 173 : A = U152_OE_N ; B = GND

U20  M24M02DRMN6TP  M24M02-DRMN6TP IC  pkg SOIC8XH  page 344
  DU1  = NC
  DU2  = NC
  E2  = U20_E2
  VSS  = GND
  SDA  = SMB_RT_CPU1_P2_ROM_SDA
  SCL  = SMB_RT_CPU1_P2_ROM_SCL
  WC_N  = GND
  VCC  = P1V8_CPU1_RT_1D

(kicad_pcb
	(version 20260206)
	(generator "pcbnew")
	(generator_version "10.0")
	(general
		(thickness 1.6)
		(legacy_teardrops no)
	)
	(paper "A4")
	(title_block
		(title "04192023_DAF0TMB3IC0_F0TG_MB_C_brd_V02_OCP.brd")
		(comment 1 "Grand Teton / footprints 1364-1365 of 8354")
	)
	(layers
		(0 "F.Cu" signal "TOP")
		(4 "In1.Cu" signal "GND")
		(6 "In2.Cu" signal "IN1")
		(8 "In3.Cu" signal "GND1")
		(10 "In4.Cu" signal "IN2")
		(12 "In5.Cu" signal "GND2")
		(14 "In6.Cu" signal "IN3")
		(16 "In7.Cu" signal "GND3")
		(18 "In8.Cu" signal "VCC")
		(20 "In9.Cu" signal "VCC1")
		(22 "In10.Cu" signal "GND4")
		(24 "In11.Cu" signal "IN4")
		(26 "In12.Cu" signal "GND5")
		(28 "In13.Cu" signal "IN5")
		(30 "In14.Cu" signal "GND6")
		(32 "In15.Cu" signal "IN6")
		(34 "In16.Cu" signal "GND7")
		(2 "B.Cu" signal "BOTTOM")
		(9 "F.Adhes" user "F.Adhesive")
		(11 "B.Adhes" user "B.Adhesive")
		(13 "F.Paste" user "Package Geometry/Pastemask Top")
		(15 "B.Paste" user "Package Geometry/Pastemask Bottom")
		(5 "F.SilkS" user "Ref Des/Silkscreen Top")
		(7 "B.SilkS" user "Ref Des/Silkscreen Bottom")
		(1 "F.Mask" user "Board Geometry/Soldermask Top")
		(3 "B.Mask" user "Board Geometry/Soldermask Bottom")
		(17 "Dwgs.User" user "User.Drawings")
		(19 "Cmts.User" user "User.Comments")
		(21 "Eco1.User" user "User.Eco1")
		(23 "Eco2.User" user "User.Eco2")
		(25 "Edge.Cuts" user "Board Geometry/Outline")
		(27 "Margin" user)
		(31 "F.CrtYd" user "Package Geometry/Place Bound Top")
		(29 "B.CrtYd" user "Package Geometry/Place Bound Bottom")
		(35 "F.Fab" user "Ref Des/Assembly Top")
		(33 "B.Fab" user "Ref Des/Assembly Bottom")
	)
	(footprint ""
		(layer "F.Cu")
		(at 164.283136 -423.816526 -90)
		(property "Reference" "U20"
			(at -0.383286 -3.052826 90)
			(unlocked yes)
			(layer "F.SilkS")
			(effects
				(font
					(size 0.7874 0.5842)
					(thickness 0.1524)
				)
				(justify left)
			)
		)
		(property "Value" ""
			(at 0 0 270)
			(layer "F.Fab")
			(effects
				(font
					(size 1.27 1.27)
				)
			)
		)
		(duplicate_pad_numbers_are_jumpers no)
		(fp_line
			(start -1.8288 2.500122)
			(end 1.8288 2.500122)
			(stroke
				(width 0.1524)
				(type default)
			)
			(layer "F.SilkS")
		)
		(fp_line
			(start 1.8288 2.500122)
			(end 1.8288 -2.500122)
			(stroke
				(width 0.1524)
				(type default)
			)
			(layer "F.SilkS")
		)
		(fp_line
			(start 0 -1.4224)
			(end -1.077722 -2.500122)
			(stroke
				(width 0.1524)
				(type default)
			)
			(layer "F.SilkS")
		)
		(fp_line
			(start -1.8288 -2.500122)
			(end -1.8288 2.500122)
			(stroke
				(width 0.1524)
				(type default)
			)
			(layer "F.SilkS")
		)
		(fp_line
			(start -1.077722 -2.500122)
			(end -1.8288 -2.500122)
			(stroke
				(width 0.1524)
				(type default)
			)
			(layer "F.SilkS")
		)
		(fp_line
			(start 1.077722 -2.500122)
			(end 0 -1.4224)
			(stroke
				(width 0.1524)
				(type default)
			)
			(layer "F.SilkS")
		)
		(fp_line
			(start 1.8288 -2.500122)
			(end 1.077722 -2.500122)
			(stroke
				(width 0.1524)
				(type default)
			)
			(layer "F.SilkS")
		)
		(fp_poly
			(pts
				(xy -3.64236 -3.590036) (xy -4.309364 -2.823718) (xy -3.209544 -2.54)
			)
			(stroke
				(width 0)
				(type default)
			)
			(fill yes)
			(layer "F.SilkS")
		)
		(fp_line
			(start -1.999996 2.500122)
			(end 1.999996 2.500122)
			(stroke
				(width 0.1)
				(type default)
			)
			(layer "F.Fab")
		)
		(fp_line
			(start 1.999996 2.500122)
			(end 1.999996 -2.500122)
			(stroke
				(width 0.1)
				(type default)
			)
			(layer "F.Fab")
		)
		(fp_line
			(start -1.999996 -2.500122)
			(end -1.999996 2.500122)
			(stroke
				(width 0.1)
				(type default)
			)
			(layer "F.Fab")
		)
		(fp_line
			(start 1.999996 -2.500122)
			(end -1.999996 -2.500122)
			(stroke
				(width 0.1)
				(type default)
			)
			(layer "F.Fab")
		)
		(fp_poly
			(pts
				(xy -4.5085 -2.413) (xy -4.5085 -1.397) (xy -3.4925 -1.905)
			)
			(stroke
				(width 0)
				(type default)
			)
			(fill yes)
			(layer "F.Fab")
		)
		(pad "1" smd rect
			(at -2.599944 -1.905 180)
			(size 0.889 1.27)
			(layers "F.Cu" "F.Mask" "F.Paste")
			(net "Net_10835")
		)
		(pad "2" smd rect
			(at -2.599944 -0.635 180)
			(size 0.889 1.27)
			(layers "F.Cu" "F.Mask" "F.Paste")
			(net "Net_10834")
		)
		(pad "3" smd rect
			(at -2.599944 0.635 180)
			(size 0.889 1.27)
			(layers "F.Cu" "F.Mask" "F.Paste")
			(net "U20_E2")
		)
		(pad "4" smd rect
			(at -2.599944 1.905 180)
			(size 0.889 1.27)
			(layers "F.Cu" "F.Mask" "F.Paste")
			(net "GND")
		)
		(pad "5" smd rect
			(at 2.599944 1.905 180)
			(size 0.889 1.27)
			(layers "F.Cu" "F.Mask" "F.Paste")
			(net "SMB_RT_CPU1_P2_ROM_SDA")
		)
		(pad "6" smd rect
			(at 2.599944 0.635 180)
			(size 0.889 1.27)
			(layers "F.Cu" "F.Mask" "F.Paste")
			(net "SMB_RT_CPU1_P2_ROM_SCL")
		)
		(pad "7" smd rect
			(at 2.599944 -0.635 180)
			(size 0.889 1.27)
			(layers "F.Cu" "F.Mask" "F.Paste")
			(net "GND")
		)
		(pad "8" smd rect
			(at 2.599944 -1.905 180)
			(size 0.889 1.27)
			(layers "F.Cu" "F.Mask" "F.Paste")
			(net "P1V8_CPU1_RT_1D")
		)
	)
	(footprint ""
		(layer "F.Cu")
		(at 134.189216 -53.974238 -90)
		(property "Reference" "R1637"
			(at 0 0 270)
			(layer "F.SilkS")
			(hide yes)
			(effects
				(font
					(size 1.27 1.27)
				)
			)
		)
		(property "Value" ""
			(at 0 0 270)
			(layer "F.Fab")
			(effects
				(font
					(size 1.27 1.27)
				)
			)
		)
		(duplicate_pad_numbers_are_jumpers no)
		(fp_line
			(start -0.7874 0.4064)
			(end -0.7874 -0.4064)
			(stroke
				(width 0.1524)
				(type default)
			)
			(layer "F.SilkS")
		)
		(fp_line
			(start 0.7874 0.4064)
			(end -0.7874 0.4064)
			(stroke
				(width 0.1524)
				(type default)
			)
			(layer "F.SilkS")
		)
		(fp_line
			(start -0.7874 -0.4064)
			(end 0.7874 -0.4064)
			(stroke
				(width 0.1524)
				(type default)
			)
			(layer "F.SilkS")
		)
		(fp_line
			(start 0.7874 -0.4064)
			(end 0.7874 0.4064)
			(stroke
				(width 0.1524)
				(type default)
			)
			(layer "F.SilkS")
		)
		(fp_line
			(start -0.67945 0.3048)
			(end -0.67945 -0.305054)
			(stroke
				(width 0.1)
				(type default)
			)
			(layer "F.Fab")
		)
		(fp_line
			(start -0.12065 0.3048)
			(end -0.67945 0.3048)
			(stroke
				(width 0.1)
				(type default)
			)
			(layer "F.Fab")
		)
		(fp_line
			(start 0.120396 0.3048)
			(end 0.120396 0.2794)
			(stroke
				(width 0.1)
				(type default)
			)
			(layer "F.Fab")
		)
		(fp_line
			(start 0.67945 0.3048)
			(end 0.120396 0.3048)
			(stroke
				(width 0.1)
				(type default)
			)
			(layer "F.Fab")
		)
		(fp_line
			(start -0.12065 0.2794)
			(end -0.12065 0.3048)
			(stroke
				(width 0.1)
				(type default)
			)
			(layer "F.Fab")
		)
		(fp_line
			(start 0.120396 0.2794)
			(end -0.12065 0.2794)
			(stroke
				(width 0.1)
				(type default)
			)
			(layer "F.Fab")
		)
		(fp_line
			(start -0.12065 -0.2794)
			(end 0.12065 -0.2794)
			(stroke
				(width 0.1)
				(type default)
			)
			(layer "F.Fab")
		)
		(fp_line
			(start 0.12065 -0.2794)
			(end 0.12065 -0.3048)
			(stroke
				(width 0.1)
				(type default)
			)
			(layer "F.Fab")
		)
		(fp_line
			(start 0.12065 -0.3048)
			(end 0.67945 -0.3048)
			(stroke
				(width 0.1)
				(type default)
			)
			(layer "F.Fab")
		)
		(fp_line
			(start 0.67945 -0.3048)
			(end 0.67945 0.3048)
			(stroke
				(width 0.1)
				(type default)
			)
			(layer "F.Fab")
		)
		(fp_line
			(start -0.67945 -0.305054)
			(end -0.12065 -0.305054)
			(stroke
				(width 0.1)
				(type default)
			)
			(layer "F.Fab")
		)
		(fp_line
			(start -0.12065 -0.305054)
			(end -0.12065 -0.2794)
			(stroke
				(width 0.1)
				(type default)
			)
			(layer "F.Fab")
		)
		(pad "1" smd circle
			(at -0.40005 0 270)
			(size 0 0)
			(layers "F.Cu" "F.Mask" "F.Paste")
			(net "U152_OE_N")
		)
		(pad "2" smd circle
			(at 0.40005 0 270)
			(size 0 0)
			(layers "F.Cu" "F.Mask" "F.Paste")
			(net "GND")
		)
	)
)
